# BASEBOARD_FAB2 (Tioga Pass) — schematic netlist excerpt (pin names and nets, part order shuffled) for the footprints in the layout excerpt that follows; sources: Cadence DE-HDL packaged netlist, KiCad conversion of Wiwynn_Tioga_Pass_MB.brd

J9T1  SCONN288_H44441003  SCONN  pkg PIP  page 78
  \12v\(1)  = P12V_NVDIMM_GHJ
  VSS(93)  = GND
  DQ(4)  = M_G_DQ<4>
  VSS(92)  = GND
  DQ(0)  = M_G_DQ<0>
  VSS(91)  = GND
  DQS9P  = M_G_DQS_DP<9>
  DQS9N  = M_G_DQS_DN<9>
  VSS(90)  = GND
  DQ(6)  = M_G_DQ<6>
  VSS(89)  = GND
  DQ(2)  = M_G_DQ<2>
  VSS(88)  = GND
  DQ(12)  = M_G_DQ<12>
  VSS(87)  = GND
  DQ(8)  = M_G_DQ<8>
  VSS(86)  = GND
  DQS10P  = M_G_DQS_DP<10>
  DQS10N  = M_G_DQS_DN<10>
  VSS(85)  = GND
  DQ(14)  = M_G_DQ<14>
  VSS(84)  = GND
  DQ(10)  = M_G_DQ<10>
  VSS(83)  = GND
  DQ(20)  = M_G_DQ<20>
  VSS(82)  = GND
  DQ(16)  = M_G_DQ<16>
  VSS(81)  = GND
  DQS11P  = M_G_DQS_DP<11>
  DQS11N  = M_G_DQS_DN<11>
  VSS(80)  = GND
  DQ(22)  = M_G_DQ<22>
  VSS(79)  = GND
  DQ(18)  = M_G_DQ<18>
  VSS(78)  = GND
  DQ(28)  = M_G_DQ<28>
  VSS(77)  = GND
  DQ(24)  = M_G_DQ<24>
  VSS(76)  = GND
  DQS12P  = M_G_DQS_DP<12>
  DQS12N  = M_G_DQS_DN<12>
  VSS(75)  = GND
  DQ(30)  = M_G_DQ<30>
  VSS(74)  = GND
  DQ(26)  = M_G_DQ<26>
  VSS(73)  = GND
  CB(4)  = M_G_ECC<4>
  VSS(72)  = GND
  CB(0)  = M_G_ECC<0>
  VSS(71)  = GND
  DQS17P  = M_G_DQS_DP<17>
  DQS17N  = M_G_DQS_DN<17>
  VSS(70)  = GND
  CB(6)  = M_G_ECC<6>
  VSS(69)  = GND
  CB(2)  = M_G_ECC<2>
  VSS(68)  = GND
  RESET_N  = M_GHJ_RST_N
  VDD(25)  = PVDDQ_GHJ
  CKE(0)  = M_G_CKE<2>
  VDD(24)  = PVDDQ_GHJ
  ACT_N  = M_G_ACT_N
  BG(0)  = M_G_BG<0>
  VDD(23)  = PVDDQ_GHJ
  A12  = M_G_MA<12>
  A9  = M_G_MA<9>
  VDD(22)  = PVDDQ_GHJ
  A8  = M_G_MA<8>
  A6  = M_G_MA<6>
  VDD(21)  = PVDDQ_GHJ
  A3  = M_G_MA<3>
  A1  = M_G_MA<1>
  VDD(20)  = PVDDQ_GHJ
  CK0P  = M_G_CLK_DP<2>
  CK0N  = M_G_CLK_DN<2>
  VDD(19)  = PVDDQ_GHJ
  VTT(1)  = PVTT_GHJ
  EVENT_N  = FM_DIMM_EVENT_COD_N
  A0  = M_G_MA<0>
  VDD(18)  = PVDDQ_GHJ
  BA(0)  = M_G_BA<0>
  A16_RAS_N  = M_G_MA<16>
  VDD(17)  = PVDDQ_GHJ
  S0_N  = M_G_CS_N<4>
  VDD(16)  = PVDDQ_GHJ
  A15_CAS_N  = M_G_MA<15>
  ODT(0)  = M_G_ODT<2>
  VDD(15)  = PVDDQ_GHJ
  S1_N  = M_G_CS_N<5>
  VDD(14)  = PVDDQ_GHJ
  ODT(1)  = M_G_ODT<3>
  VDD(13)  = PVDDQ_GHJ
  S2_N_C(0)  = M_G_CS_N<6>
  VSS(67)  = GND
  DQ(36)  = M_G_DQ<36>
  VSS(66)  = GND
  DQ(32)  = M_G_DQ<32>
  VSS(65)  = GND
  DQS13P  = M_G_DQS_DP<13>
  DQS13N  = M_G_DQS_DN<13>
  VSS(64)  = GND
  DQ(38)  = M_G_DQ<38>
  VSS(63)  = GND
  DQ(34)  = M_G_DQ<34>
  VSS(62)  = GND
  DQ(44)  = M_G_DQ<44>
  VSS(61)  = GND
  DQ(40)  = M_G_DQ<40>
  VSS(60)  = GND
  DQS14P  = M_G_DQS_DP<14>
  DQS14N  = M_G_DQS_DN<14>
  VSS(59)  = GND
  DQ(46)  = M_G_DQ<46>
  VSS(58)  = GND
  DQ(42)  = M_G_DQ<42>
  VSS(57)  = GND
  DQ(52)  = M_G_DQ<52>
  VSS(56)  = GND
  DQ(48)  = M_G_DQ<48>
  VSS(55)  = GND
  DQS15P  = M_G_DQS_DP<15>
  DQS15N  = M_G_DQS_DN<15>
  VSS(54)  = GND
  DQ(54)  = M_G_DQ<54>
  VSS(53)  = GND
  DQ(50)  = M_G_DQ<50>
  VSS(52)  = GND
  DQ(60)  = M_G_DQ<60>
  VSS(51)  = GND
  DQ(56)  = M_G_DQ<56>
  VSS(50)  = GND
  DQS16P  = M_G_DQS_DP<16>
  DQS16N  = M_G_DQS_DN<16>
  VSS(49)  = GND
  DQ(62)  = M_G_DQ<62>
  VSS(48)  = GND
  DQ(58)  = M_G_DQ<58>
  VSS(47)  = GND
  SA(0)  = PVPP_GHJ
  SA(1)  = GND
  SCL  = SMB_DDR_GHJ_VPP_SCL
  VPP(4)  = PVPP_GHJ
  VPP(3)  = PVPP_GHJ
  RFU(2)  = TP_CH_G_DIMM0_RFU_2
  \12v\(0)  = P12V_NVDIMM_GHJ
  VREFCA  = M_G_VREF
  VSS(46)  = GND
  DQ(5)  = M_G_DQ<5>
  VSS(45)  = GND
  DQ(1)  = M_G_DQ<1>
  VSS(44)  = GND
  DQS0N  = M_G_DQS_DN<0>
  DQS0P  = M_G_DQS_DP<0>
  VSS(43)  = GND
  DQ(7)  = M_G_DQ<7>
  VSS(42)  = GND
  DQ(3)  = M_G_DQ<3>
  VSS(41)  = GND
  DQ(13)  = M_G_DQ<13>
  VSS(40)  = GND
  DQ(9)  = M_G_DQ<9>
  VSS(39)  = GND
  DQS1N  = M_G_DQS_DN<1>
  DQS1P  = M_G_DQS_DP<1>
  VSS(38)  = GND
  DQ(15)  = M_G_DQ<15>
  VSS(37)  = GND
  DQ(11)  = M_G_DQ<11>
  VSS(36)  = GND
  DQ(21)  = M_G_DQ<21>
  VSS(35)  = GND
  DQ(17)  = M_G_DQ<17>
  VSS(34)  = GND
  DQS2N  = M_G_DQS_DN<2>
  DQS2P  = M_G_DQS_DP<2>
  VSS(33)  = GND
  DQ(23)  = M_G_DQ<23>
  VSS(32)  = GND
  DQ(19)  = M_G_DQ<19>
  VSS(31)  = GND
  DQ(29)  = M_G_DQ<29>
  VSS(30)  = GND
  DQ(25)  = M_G_DQ<25>
  VSS(29)  = GND
  DQS3N  = M_G_DQS_DN<3>
  DQS3P  = M_G_DQS_DP<3>
  VSS(28)  = GND
  DQ(31)  = M_G_DQ<31>
  VSS(27)  = GND
  DQ(27)  = M_G_DQ<27>
  VSS(26)  = GND
  CB(5)  = M_G_ECC<5>
  VSS(25)  = GND
  CB(1)  = M_G_ECC<1>
  VSS(24)  = GND
  DQS8N  = M_G_DQS_DN<8>
  DQS8P  = M_G_DQS_DP<8>
  VSS(23)  = GND
  CB(7)  = M_G_ECC<7>
  VSS(22)  = GND
  CB(3)  = M_G_ECC<3>
  VSS(21)  = GND
  CKE(1)  = M_G_CKE<3>
  VDD(12)  = PVDDQ_GHJ
  RFU(0)  = TP_CH_G_DIMM0_RFU_0
  VDD(11)  = PVDDQ_GHJ
  BG(1)  = M_G_BG<1>
  ALERT_N  = M_G_ALERT_N
  VDD(10)  = PVDDQ_GHJ
  A11  = M_G_MA<11>
  A7  = M_G_MA<7>
  VDD(9)  = PVDDQ_GHJ
  A5  = M_G_MA<5>
  A4  = M_G_MA<4>
  VDD(8)  = PVDDQ_GHJ
  A2  = M_G_MA<2>
  VDD(7)  = PVDDQ_GHJ
  CK1P  = M_G_CLK_DP<3>
  CK1N  = M_G_CLK_DN<3>
  VDD(6)  = PVDDQ_GHJ
  VTT(0)  = PVTT_GHJ
  PAR  = M_G_PAR
  VDD(5)  = PVDDQ_GHJ
  BA(1)  = M_G_BA<1>
  A10  = M_G_MA<10>
  VDD(4)  = PVDDQ_GHJ
  RFU(1)  = TP_CH_G_DIMM0_RFU_1
  A14_WE_N  = M_G_MA<14>
  VDD(3)  = PVDDQ_GHJ
  SAVE_N_NC  = FM_ADR_COMPLETE_GHJ_N
  VDD(2)  = PVDDQ_GHJ
  A13  = M_G_MA<13>
  VDD(1)  = PVDDQ_GHJ
  A17  = M_G_MA<17>
  C(2)  = M_G_C<2>
  VDD(0)  = PVDDQ_GHJ
  S3_N_C(1)  = M_G_CS_N<7>
  SA(2)  = GND
  VSS(20)  = GND
  DQ(37)  = M_G_DQ<37>
  VSS(19)  = GND
  DQ(33)  = M_G_DQ<33>
  VSS(18)  = GND
  DQS4N  = M_G_DQS_DN<4>
  DQS4P  = M_G_DQS_DP<4>
  VSS(17)  = GND
  DQ(39)  = M_G_DQ<39>
  VSS(16)  = GND
  DQ(35)  = M_G_DQ<35>
  VSS(15)  = GND
  DQ(45)  = M_G_DQ<45>
  VSS(14)  = GND
  DQ(41)  = M_G_DQ<41>
  VSS(13)  = GND
  DQS5N  = M_G_DQS_DN<5>
  DQS5P  = M_G_DQS_DP<5>
  VSS(12)  = GND
  DQ(47)  = M_G_DQ<47>
  VSS(11)  = GND
  DQ(43)  = M_G_DQ<43>
  VSS(10)  = GND
  DQ(53)  = M_G_DQ<53>
  VSS(9)  = GND
  DQ(49)  = M_G_DQ<49>
  VSS(8)  = GND
  DQS6N  = M_G_DQS_DN<6>
  DQS6P  = M_G_DQS_DP<6>
  VSS(7)  = GND
  DQ(55)  = M_G_DQ<55>
  VSS(6)  = GND
  DQ(51)  = M_G_DQ<51>
  VSS(5)  = GND
  DQ(61)  = M_G_DQ<61>
  VSS(4)  = GND
  DQ(57)  = M_G_DQ<57>
  VSS(3)  = GND
  DQS7N  = M_G_DQS_DN<7>
  DQS7P  = M_G_DQS_DP<7>
  VSS(2)  = GND
  DQ(63)  = M_G_DQ<63>
  VSS(1)  = GND
  DQ(59)  = M_G_DQ<59>
  VSS(0)  = GND
  VDDSPD  = PVPP_GHJ
  SDA  = SMB_DDR_GHJ_VPP_SDA
  VPP(1)  = PVPP_GHJ
  VPP(0)  = PVPP_GHJ
  VPP(2)  = PVPP_GHJ

(kicad_pcb
	(version 20260206)
	(generator "pcbnew")
	(generator_version "10.0")
	(general
		(thickness 1.6)
		(legacy_teardrops no)
	)
	(paper "A4")
	(title_block
		(title "Wiwynn_Tioga_Pass_MB.brd")
		(comment 1 "Tioga Pass / footprint 4084 of 4770 (J9T1), pads 202-249 of 291")
	)
	(layers
		(0 "F.Cu" signal "TOP")
		(4 "In1.Cu" signal "L2GND")
		(6 "In2.Cu" signal "L3")
		(8 "In3.Cu" signal "L4GND")
		(10 "In4.Cu" signal "L5")
		(12 "In5.Cu" signal "L6GND")
		(14 "In6.Cu" signal "L7VCC")
		(16 "In7.Cu" signal "L8VCC")
		(18 "In8.Cu" signal "L9GND")
		(20 "In9.Cu" signal "L10")
		(22 "In10.Cu" signal "L11GND")
		(24 "In11.Cu" signal "L12")
		(26 "In12.Cu" signal "L13GND")
		(2 "B.Cu" signal "BOTTOM")
		(9 "F.Adhes" user "F.Adhesive")
		(11 "B.Adhes" user "B.Adhesive")
		(13 "F.Paste" user "Package Geometry/Pastemask Top")
		(15 "B.Paste" user "Package Geometry/Pastemask Bottom")
		(5 "F.SilkS" user "Ref Des/Silkscreen Top")
		(7 "B.SilkS" user "Ref Des/Silkscreen Bottom")
		(1 "F.Mask" user "Board Geometry/Soldermask Top")
		(3 "B.Mask" user "Board Geometry/Soldermask Bottom")
		(17 "Dwgs.User" user "User.Drawings")
		(19 "Cmts.User" user "User.Comments")
		(21 "Eco1.User" user "User.Eco1")
		(23 "Eco2.User" user "User.Eco2")
		(25 "Edge.Cuts" user "Board Geometry/Outline")
		(27 "Margin" user)
		(31 "F.CrtYd" user "Package Geometry/Place Bound Top")
		(29 "B.CrtYd" user "Package Geometry/Place Bound Bottom")
		(35 "F.Fab" user "Ref Des/Assembly Top")
		(33 "B.Fab" user "Ref Des/Assembly Bottom")
	)
	(footprint ""
		(layer "B.Cu")
		(at 29.699458 -24.824182 90)
		(property "Reference" "J9T1"
			(at 2.200148 39.261542 0)
			(unlocked yes)
			(layer "B.SilkS")
			(effects
				(font
					(size 0.7874 0.5842)
					(thickness 0.1524)
				)
				(justify left mirror)
			)
		)
		(property "Value" ""
			(at 0 0 90)
			(layer "B.Fab")
			(effects
				(font
					(size 1.27 1.27)
				)
				(justify mirror)
			)
		)
		(duplicate_pad_numbers_are_jumpers no)
		(pad "199" smd rect
			(at -4.59994 45.900086 270)
			(size 1.8034 0.508)
			(layers "B.Cu" "B.Mask" "B.Paste")
			(net "M_G_ECC<7>")
		)
		(pad "200" smd rect
			(at -4.59994 46.74997 270)
			(size 1.8034 0.508)
			(layers "B.Cu" "B.Mask" "B.Paste")
			(net "GND")
		)
		(pad "201" smd rect
			(at -4.59994 47.600108 270)
			(size 1.8034 0.508)
			(layers "B.Cu" "B.Mask" "B.Paste")
			(net "M_G_ECC<3>")
		)
		(pad "202" smd rect
			(at -4.59994 48.449992 270)
			(size 1.8034 0.508)
			(layers "B.Cu" "B.Mask" "B.Paste")
			(net "GND")
		)
		(pad "203" smd rect
			(at -4.59994 49.299876 270)
			(size 1.8034 0.508)
			(layers "B.Cu" "B.Mask" "B.Paste")
			(net "M_G_CKE<3>")
		)
		(pad "204" smd rect
			(at -4.59994 50.150014 270)
			(size 1.8034 0.508)
			(layers "B.Cu" "B.Mask" "B.Paste")
			(net "PVDDQ_GHJ")
		)
		(pad "205" smd rect
			(at -4.59994 50.999898 270)
			(size 1.8034 0.508)
			(layers "B.Cu" "B.Mask" "B.Paste")
			(net "TP_CH_G_DIMM0_RFU_0")
		)
		(pad "206" smd rect
			(at -4.59994 51.850036 270)
			(size 1.8034 0.508)
			(layers "B.Cu" "B.Mask" "B.Paste")
			(net "PVDDQ_GHJ")
		)
		(pad "207" smd rect
			(at -4.59994 52.69992 270)
			(size 1.8034 0.508)
			(layers "B.Cu" "B.Mask" "B.Paste")
			(net "M_G_BG<1>")
		)
		(pad "208" smd rect
			(at -4.59994 53.550058 270)
			(size 1.8034 0.508)
			(layers "B.Cu" "B.Mask" "B.Paste")
			(net "M_G_ALERT_N")
		)
		(pad "209" smd rect
			(at -4.59994 54.399942 270)
			(size 1.8034 0.508)
			(layers "B.Cu" "B.Mask" "B.Paste")
			(net "PVDDQ_GHJ")
		)
		(pad "210" smd rect
			(at -4.59994 55.25008 270)
			(size 1.8034 0.508)
			(layers "B.Cu" "B.Mask" "B.Paste")
			(net "M_G_MA<11>")
		)
		(pad "211" smd rect
			(at -4.59994 56.099964 270)
			(size 1.8034 0.508)
			(layers "B.Cu" "B.Mask" "B.Paste")
			(net "M_G_MA<7>")
		)
		(pad "212" smd rect
			(at -4.59994 56.950102 270)
			(size 1.8034 0.508)
			(layers "B.Cu" "B.Mask" "B.Paste")
			(net "PVDDQ_GHJ")
		)
		(pad "213" smd rect
			(at -4.59994 57.799986 270)
			(size 1.8034 0.508)
			(layers "B.Cu" "B.Mask" "B.Paste")
			(net "M_G_MA<5>")
		)
		(pad "214" smd rect
			(at -4.59994 58.650124 270)
			(size 1.8034 0.508)
			(layers "B.Cu" "B.Mask" "B.Paste")
			(net "M_G_MA<4>")
		)
		(pad "215" smd rect
			(at -4.59994 59.500008 270)
			(size 1.8034 0.508)
			(layers "B.Cu" "B.Mask" "B.Paste")
			(net "PVDDQ_GHJ")
		)
		(pad "216" smd rect
			(at -4.59994 60.349892 270)
			(size 1.8034 0.508)
			(layers "B.Cu" "B.Mask" "B.Paste")
			(net "M_G_MA<2>")
		)
		(pad "217" smd rect
			(at -4.59994 61.20003 270)
			(size 1.8034 0.508)
			(layers "B.Cu" "B.Mask" "B.Paste")
			(net "PVDDQ_GHJ")
		)
		(pad "218" smd rect
			(at -4.59994 62.049914 270)
			(size 1.8034 0.508)
			(layers "B.Cu" "B.Mask" "B.Paste")
			(net "M_G_CLK_DP<3>")
		)
		(pad "219" smd rect
			(at -4.59994 62.900052 270)
			(size 1.8034 0.508)
			(layers "B.Cu" "B.Mask" "B.Paste")
			(net "M_G_CLK_DN<3>")
		)
		(pad "220" smd rect
			(at -4.59994 63.749936 270)
			(size 1.8034 0.508)
			(layers "B.Cu" "B.Mask" "B.Paste")
			(net "PVDDQ_GHJ")
		)
		(pad "221" smd rect
			(at -4.59994 64.600074 270)
			(size 1.8034 0.508)
			(layers "B.Cu" "B.Mask" "B.Paste")
			(net "PVTT_GHJ")
		)
		(pad "222" smd rect
			(at -4.59994 70.550024 270)
			(size 1.8034 0.508)
			(layers "B.Cu" "B.Mask" "B.Paste")
			(net "M_G_PAR")
		)
		(pad "223" smd rect
			(at -4.59994 71.399908 270)
			(size 1.8034 0.508)
			(layers "B.Cu" "B.Mask" "B.Paste")
			(net "PVDDQ_GHJ")
		)
		(pad "224" smd rect
			(at -4.59994 72.250046 270)
			(size 1.8034 0.508)
			(layers "B.Cu" "B.Mask" "B.Paste")
			(net "M_G_BA<1>")
		)
		(pad "225" smd rect
			(at -4.59994 73.09993 270)
			(size 1.8034 0.508)
			(layers "B.Cu" "B.Mask" "B.Paste")
			(net "M_G_MA<10>")
		)
		(pad "226" smd rect
			(at -4.59994 73.950068 270)
			(size 1.8034 0.508)
			(layers "B.Cu" "B.Mask" "B.Paste")
			(net "PVDDQ_GHJ")
		)
		(pad "227" smd rect
			(at -4.59994 74.799952 270)
			(size 1.8034 0.508)
			(layers "B.Cu" "B.Mask" "B.Paste")
			(net "TP_CH_G_DIMM0_RFU_1")
		)
		(pad "228" smd rect
			(at -4.59994 75.65009 270)
			(size 1.8034 0.508)
			(layers "B.Cu" "B.Mask" "B.Paste")
			(net "M_G_MA<14>")
		)
		(pad "229" smd rect
			(at -4.59994 76.499974 270)
			(size 1.8034 0.508)
			(layers "B.Cu" "B.Mask" "B.Paste")
			(net "PVDDQ_GHJ")
		)
		(pad "230" smd rect
			(at -4.59994 77.350112 270)
			(size 1.8034 0.508)
			(layers "B.Cu" "B.Mask" "B.Paste")
			(net "FM_ADR_COMPLETE_GHJ_N")
		)
		(pad "231" smd rect
			(at -4.59994 78.199996 270)
			(size 1.8034 0.508)
			(layers "B.Cu" "B.Mask" "B.Paste")
			(net "PVDDQ_GHJ")
		)
		(pad "232" smd rect
			(at -4.59994 79.04988 270)
			(size 1.8034 0.508)
			(layers "B.Cu" "B.Mask" "B.Paste")
			(net "M_G_MA<13>")
		)
		(pad "233" smd rect
			(at -4.59994 79.900018 270)
			(size 1.8034 0.508)
			(layers "B.Cu" "B.Mask" "B.Paste")
			(net "PVDDQ_GHJ")
		)
		(pad "234" smd rect
			(at -4.59994 80.749902 270)
			(size 1.8034 0.508)
			(layers "B.Cu" "B.Mask" "B.Paste")
			(net "M_G_MA<17>")
		)
		(pad "235" smd rect
			(at -4.59994 81.60004 270)
			(size 1.8034 0.508)
			(layers "B.Cu" "B.Mask" "B.Paste")
			(net "M_G_C<2>")
		)
		(pad "236" smd rect
			(at -4.59994 82.449924 270)
			(size 1.8034 0.508)
			(layers "B.Cu" "B.Mask" "B.Paste")
			(net "PVDDQ_GHJ")
		)
		(pad "237" smd rect
			(at -4.59994 83.300062 270)
			(size 1.8034 0.508)
			(layers "B.Cu" "B.Mask" "B.Paste")
			(net "M_G_CS_N<7>")
		)
		(pad "238" smd rect
			(at -4.59994 84.149946 270)
			(size 1.8034 0.508)
			(layers "B.Cu" "B.Mask" "B.Paste")
			(net "GND")
		)
		(pad "239" smd rect
			(at -4.59994 85.000084 270)
			(size 1.8034 0.508)
			(layers "B.Cu" "B.Mask" "B.Paste")
			(net "GND")
		)
		(pad "240" smd rect
			(at -4.59994 85.849968 270)
			(size 1.8034 0.508)
			(layers "B.Cu" "B.Mask" "B.Paste")
			(net "M_G_DQ<37>")
		)
		(pad "241" smd rect
			(at -4.59994 86.700106 270)
			(size 1.8034 0.508)
			(layers "B.Cu" "B.Mask" "B.Paste")
			(net "GND")
		)
		(pad "242" smd rect
			(at -4.59994 87.54999 270)
			(size 1.8034 0.508)
			(layers "B.Cu" "B.Mask" "B.Paste")
			(net "M_G_DQ<33>")
		)
		(pad "243" smd rect
			(at -4.59994 88.399874 270)
			(size 1.8034 0.508)
			(layers "B.Cu" "B.Mask" "B.Paste")
			(net "GND")
		)
		(pad "244" smd rect
			(at -4.59994 89.250012 270)
			(size 1.8034 0.508)
			(layers "B.Cu" "B.Mask" "B.Paste")
			(net "M_G_DQS_DN<4>")
		)
		(pad "245" smd rect
			(at -4.59994 90.099896 270)
			(size 1.8034 0.508)
			(layers "B.Cu" "B.Mask" "B.Paste")
			(net "M_G_DQS_DP<4>")
		)
		(pad "246" smd rect
			(at -4.59994 90.950034 270)
			(size 1.8034 0.508)
			(layers "B.Cu" "B.Mask" "B.Paste")
			(net "GND")
		)
	)
)
